(kicad_pcb
	(version 20221018)
	(generator pcbnew)
	(general
    (thickness 1.7403)
  )
	(paper "A4")
	(title_block
    (title "Data Center RDIMM DDR4 Tester")
    (date "2024-09-30")
    (rev "1.2.4")
		(comment 9 "footprints 534-543 of 690")
	)
	(layers
    (0 "F.Cu" signal)
    (1 "In1.Cu" power)
    (2 "In2.Cu" signal)
    (3 "In3.Cu" power)
    (4 "In4.Cu" power)
    (5 "In5.Cu" signal)
    (6 "In6.Cu" power)
    (7 "In7.Cu" signal)
    (8 "In8.Cu" power)
    (9 "In9.Cu" signal)
    (10 "In10.Cu" power)
    (31 "B.Cu" signal)
    (32 "B.Adhes" user "B.Adhesive")
    (33 "F.Adhes" user "F.Adhesive")
    (34 "B.Paste" user)
    (35 "F.Paste" user)
    (36 "B.SilkS" user "B.Silkscreen")
    (37 "F.SilkS" user "F.Silkscreen")
    (38 "B.Mask" user)
    (39 "F.Mask" user)
    (40 "Dwgs.User" user "User.Drawings")
    (41 "Cmts.User" user "User.Comments")
    (42 "Eco1.User" user "User.Eco1")
    (43 "Eco2.User" user "User.Eco2")
    (44 "Edge.Cuts" user)
    (45 "Margin" user)
    (46 "B.CrtYd" user "B.Courtyard")
    (47 "F.CrtYd" user "F.Courtyard")
    (48 "B.Fab" user)
    (49 "F.Fab" user)
  )
	(footprint "data-center-rdimm-ddr4-tester-footprints:C_0402_1005Metric" (layer "B.Cu")
    (at 184.649128 57.951208 90)
    (descr "Capacitor SMD 0402")
    (tags "capacitor SMD 0402")
    (property "Author" "Antmicro")
    (property "Dielectric" "X5R")
    (property "License" "Apache-2.0")
    (property "MPN" "GRM155R61H104KE14D")
    (property "Manufacturer" "Murata")
    (property "Sheetfile" "DDR4.kicad_sch")
    (property "Sheetname" "DDR4")
    (property "Val" "100n")
    (property "Voltage" "50V")
    (property "ki_description" " ")
    (attr smd)
    (fp_text reference "C210" (at -0.878792 0.370872 270) (layer "B.SilkS")
        (effects (font (size 0.7 0.7) (thickness 0.15)) (justify left bottom mirror))
    )
    (fp_text value "C_100n_0402" (at 0 -1.4 270) (layer "B.Fab") hide
        (effects (font (size 0.7 0.7) (thickness 0.15)) (justify left bottom mirror))
    )
    (fp_text user "${REFERENCE}" (at -0.932 -3.168 270) (layer "B.Fab") hide
        (effects (font (size 0.7 0.7) (thickness 0.15)) (justify left bottom mirror))
    )
    (fp_text user "Author: Antmicro" (at -0.932 -4.17 270) (layer "B.Fab") hide
        (effects (font (size 0.7 0.7) (thickness 0.15)) (justify left bottom mirror))
    )
    (fp_text user "License: Apache-2.0" (at -0.932 -5.17 270) (layer "B.Fab") hide
        (effects (font (size 0.7 0.7) (thickness 0.15)) (justify left bottom mirror))
    )
    (fp_rect (start -0.94 0.47) (end 0.94 -0.47)
      (stroke (width 0.05) (type solid)) (fill none) (layer "B.CrtYd"))
    (fp_rect (start -0.499 0.249) (end 0.499 -0.249)
      (stroke (width 0.15) (type solid)) (fill none) (layer "B.Fab"))
    (pad "1" smd roundrect (at -0.484 0 90) (size 0.59 0.64) (layers "B.Cu" "B.Paste" "B.Mask") (roundrect_rratio 0.25)
      (net 77 "VDDQ") (pintype "passive"))
    (pad "2" smd roundrect (at 0.484 0 90) (size 0.59 0.64) (layers "B.Cu" "B.Paste" "B.Mask") (roundrect_rratio 0.25)
      (net 9 "GND") (pintype "passive"))
  )
	(footprint "data-center-rdimm-ddr4-tester-footprints:R_0402_1005Metric" (layer "B.Cu")
    (at 122.736328 103.500008 -90)
    (descr "Resistor SMD 0402")
    (tags "resistor SMD 0402")
    (property "Author" "Antmicro")
    (property "Current" "1A")
    (property "License" "Apache-2.0")
    (property "MPN" "ERJ2GE0R00X")
    (property "Manufacturer" "Panasonic")
    (property "Sheetfile" "supply.kicad_sch")
    (property "Sheetname" "Supply")
    (property "Tolerance" "")
    (property "Val" "0R")
    (property "ki_description" "0R resistor in 0402 package with unspecified tolerance")
    (attr smd)
    (fp_text reference "R47" (at -0.980008 0.576328 90) (layer "B.SilkS")
        (effects (font (size 0.7 0.7) (thickness 0.15)) (justify left bottom mirror))
    )
    (fp_text value "R_0R_0402" (at 0 -1.4 90) (layer "B.Fab") hide
        (effects (font (size 0.7 0.7) (thickness 0.15)) (justify left bottom mirror))
    )
    (fp_text user "${REFERENCE}" (at -0.95 -3.168 90) (layer "B.Fab") hide
        (effects (font (size 0.7 0.7) (thickness 0.15)) (justify left bottom mirror))
    )
    (fp_text user "Author: Antmicro" (at -0.95 -4.169 90) (layer "B.Fab") hide
        (effects (font (size 0.7 0.7) (thickness 0.15)) (justify left bottom mirror))
    )
    (fp_text user "License: Apache-2.0" (at -0.95 -5.169 90) (layer "B.Fab") hide
        (effects (font (size 0.7 0.7) (thickness 0.15)) (justify left bottom mirror))
    )
    (fp_rect (start -0.93 0.47) (end 0.93 -0.47)
      (stroke (width 0.05) (type solid)) (fill none) (layer "B.CrtYd"))
    (fp_rect (start -0.5 0.25) (end 0.5 -0.25)
      (stroke (width 0.15) (type solid)) (fill none) (layer "B.Fab"))
    (pad "1" smd roundrect (at -0.485 0 270) (size 0.59 0.64) (layers "B.Cu" "B.Paste" "B.Mask") (roundrect_rratio 0.25)
      (net 153 "/Supply/VCC_IO_EN") (pintype "passive"))
    (pad "2" smd roundrect (at 0.485 0 270) (size 0.59 0.64) (layers "B.Cu" "B.Paste" "B.Mask") (roundrect_rratio 0.25)
      (net 642 "Net-(U9-EN)") (pintype "passive"))
  )
	(footprint "data-center-rdimm-ddr4-tester-footprints:R_0402_1005Metric" (layer "B.Cu")
    (at 134.386328 94.310008 90)
    (descr "Resistor SMD 0402")
    (tags "resistor SMD 0402")
    (property "Author" "Antmicro")
    (property "Current" "1A")
    (property "License" "Apache-2.0")
    (property "MPN" "ERJ2GE0R00X")
    (property "Manufacturer" "Panasonic")
    (property "Sheetfile" "supply.kicad_sch")
    (property "Sheetname" "Supply")
    (property "Tolerance" "")
    (property "Val" "0R")
    (property "ki_description" "0R resistor in 0402 package with unspecified tolerance")
    (attr smd)
    (fp_text reference "R48" (at 1.100008 1.313672 270) (layer "B.SilkS")
        (effects (font (size 0.7 0.7) (thickness 0.15)) (justify left bottom mirror))
    )
    (fp_text value "R_0R_0402" (at 0 -1.4 270) (layer "B.Fab") hide
        (effects (font (size 0.7 0.7) (thickness 0.15)) (justify left bottom mirror))
    )
    (fp_text user "Author: Antmicro" (at -0.95 -4.169 270) (layer "B.Fab") hide
        (effects (font (size 0.7 0.7) (thickness 0.15)) (justify left bottom mirror))
    )
    (fp_text user "${REFERENCE}" (at -0.95 -3.168 270) (layer "B.Fab") hide
        (effects (font (size 0.7 0.7) (thickness 0.15)) (justify left bottom mirror))
    )
    (fp_text user "License: Apache-2.0" (at -0.95 -5.169 270) (layer "B.Fab") hide
        (effects (font (size 0.7 0.7) (thickness 0.15)) (justify left bottom mirror))
    )
    (fp_rect (start -0.93 0.47) (end 0.93 -0.47)
      (stroke (width 0.05) (type solid)) (fill none) (layer "B.CrtYd"))
    (fp_rect (start -0.5 0.25) (end 0.5 -0.25)
      (stroke (width 0.15) (type solid)) (fill none) (layer "B.Fab"))
    (pad "1" smd roundrect (at -0.485 0 90) (size 0.59 0.64) (layers "B.Cu" "B.Paste" "B.Mask") (roundrect_rratio 0.25)
      (net 152 "/Supply/VCC_AUX_EN") (pintype "passive"))
    (pad "2" smd roundrect (at 0.485 0 90) (size 0.59 0.64) (layers "B.Cu" "B.Paste" "B.Mask") (roundrect_rratio 0.25)
      (net 643 "Net-(U12-EN)") (pintype "passive"))
  )
	(footprint "data-center-rdimm-ddr4-tester-footprints:Fiducial_1mm_Mask2mm" (layer "B.Cu")
    (at 252 50 180)
    (descr "Circular Fiducial, 1mm bare copper, 3mm soldermask opening")
    (tags "fiducial")
    (property "Author" "Antmicro")
    (property "License" "Apache-2.0")
    (property "MPN" "")
    (property "Manufacturer" "")
    (property "Sheetfile" "data-center-rdimm-ddr4-tester.kicad_sch")
    (property "Sheetname" "")
    (property "exclude_from_bom" "")
    (property "ki_description" "Fiducial Marker for use with single board only")
    (attr exclude_from_pos_files exclude_from_bom)
    (fp_text reference "FID6" (at -0.99 1.4) (layer "B.SilkS")
        (effects (font (size 0.7 0.7) (thickness 0.15)) (justify left bottom mirror))
    )
    (fp_text value "Fiducial_1mm_Mask2mm" (at 0 -2.2) (layer "B.Fab")
        (effects (font (size 0.7 0.7) (thickness 0.15)) (justify left bottom mirror))
    )
    (fp_text user "License: Apache-2.0" (at -1.25 -7.003) (layer "B.Fab") hide
        (effects (font (size 0.7 0.7) (thickness 0.15)) (justify left bottom mirror))
    )
    (fp_text user "Author: Antmicro" (at -1.25 -5.803) (layer "B.Fab") hide
        (effects (font (size 0.7 0.7) (thickness 0.15)) (justify left bottom mirror))
    )
    (fp_text user "${REFERENCE}" (at -1.25 -4.603) (layer "B.Fab") hide
        (effects (font (size 0.7 0.7) (thickness 0.15)) (justify left bottom mirror))
    )
    (fp_circle (center 0 0) (end 1.24 0)
      (stroke (width 0.05) (type solid)) (fill none) (layer "B.CrtYd"))
    (fp_circle (center 0 0) (end 0.999 0)
      (stroke (width 0.15) (type solid)) (fill none) (layer "B.Fab"))
    (pad "" smd circle (at 0 0 180) (size 1 1) (layers "B.Cu" "B.Mask")
      (solder_mask_margin 0.5) (clearance 0.5))
  )
	(footprint "data-center-rdimm-ddr4-tester-footprints:C_0201" (layer "B.Cu")
    (at 192.125 95.625)
    (descr "Capacitor SMD 0201")
    (tags "capacitor SMD 0201")
    (property "Author" "Antmicro")
    (property "Dielectric" "")
    (property "License" "Apache-2.0")
    (property "MPN" "CC0201KRX6S5BB104")
    (property "Manufacturer" "Yaego")
    (property "Sheetfile" "fpga-power.kicad_sch")
    (property "Sheetname" "FPGA power")
    (property "Val" "100n")
    (property "Voltage" "")
    (property "ki_description" " ")
    (attr smd)
    (fp_text reference "C244" (at 5.465 0.305 180) (layer "B.SilkS")
        (effects (font (size 0.7 0.7) (thickness 0.15)) (justify left bottom mirror))
    )
    (fp_text value "C_100n_0201" (at 0 -1.4 180) (layer "B.Fab") hide
        (effects (font (size 0.7 0.7) (thickness 0.15)) (justify left bottom mirror))
    )
    (fp_text user "${REFERENCE}" (at -0.72 -3.4 180) (layer "B.Fab") hide
        (effects (font (size 0.7 0.7) (thickness 0.15)) (justify left bottom mirror))
    )
    (fp_text user "Author: Antmicro" (at -0.72 -5.4 180) (layer "B.Fab") hide
        (effects (font (size 0.7 0.7) (thickness 0.15)) (justify left bottom mirror))
    )
    (fp_text user "License: Apache-2.0" (at -0.72 -4.4 180) (layer "B.Fab") hide
        (effects (font (size 0.7 0.7) (thickness 0.15)) (justify left bottom mirror))
    )
    (fp_rect (start -0.72 0.38) (end 0.72 -0.38)
      (stroke (width 0.05) (type solid)) (fill none) (layer "B.CrtYd"))
    (fp_rect (start 0.3 -0.15) (end -0.301 0.149)
      (stroke (width 0.15) (type solid)) (fill none) (layer "B.Fab"))
    (pad "" smd roundrect (at -0.349 0.002) (size 0.318 0.36) (layers "B.Paste") (roundrect_rratio 0.25))
    (pad "" smd roundrect (at 0.341 0.002) (size 0.318 0.36) (layers "B.Paste") (roundrect_rratio 0.25))
    (pad "1" smd roundrect (at -0.321 0.002) (size 0.46 0.4) (layers "B.Cu" "B.Mask") (roundrect_rratio 0.25)
      (net 147 "1V0_SYS") (pintype "passive"))
    (pad "2" smd roundrect (at 0.32 0.002) (size 0.46 0.4) (layers "B.Cu" "B.Mask") (roundrect_rratio 0.25)
      (net 9 "GND") (pintype "passive"))
  )
	(footprint "data-center-rdimm-ddr4-tester-footprints:C_0402_1005Metric" (layer "B.Cu")
    (at 122.4 117.55)
    (descr "Capacitor SMD 0402")
    (tags "capacitor SMD 0402")
    (property "Author" "Antmicro")
    (property "Dielectric" "X5R")
    (property "License" "Apache-2.0")
    (property "MPN" "GRM155R61H104KE14D")
    (property "Manufacturer" "Murata")
    (property "Sheetfile" "supply.kicad_sch")
    (property "Sheetname" "Supply")
    (property "Val" "100n")
    (property "Voltage" "50V")
    (property "ki_description" " ")
    (attr smd)
    (fp_text reference "C285" (at 1.57 -0.6 180) (layer "B.SilkS")
        (effects (font (size 0.7 0.7) (thickness 0.15)) (justify left bottom mirror))
    )
    (fp_text value "C_100n_0402" (at 0 -1.4 180) (layer "B.Fab") hide
        (effects (font (size 0.7 0.7) (thickness 0.15)) (justify left bottom mirror))
    )
    (fp_text user "License: Apache-2.0" (at -0.932 -5.17 180) (layer "B.Fab") hide
        (effects (font (size 0.7 0.7) (thickness 0.15)) (justify left bottom mirror))
    )
    (fp_text user "Author: Antmicro" (at -0.932 -4.17 180) (layer "B.Fab") hide
        (effects (font (size 0.7 0.7) (thickness 0.15)) (justify left bottom mirror))
    )
    (fp_text user "${REFERENCE}" (at -0.932 -3.168 180) (layer "B.Fab") hide
        (effects (font (size 0.7 0.7) (thickness 0.15)) (justify left bottom mirror))
    )
    (fp_rect (start -0.94 0.47) (end 0.94 -0.47)
      (stroke (width 0.05) (type solid)) (fill none) (layer "B.CrtYd"))
    (fp_rect (start -0.499 0.249) (end 0.499 -0.249)
      (stroke (width 0.15) (type solid)) (fill none) (layer "B.Fab"))
    (pad "1" smd roundrect (at -0.484 0) (size 0.59 0.64) (layers "B.Cu" "B.Paste" "B.Mask") (roundrect_rratio 0.25)
      (net 307 "5V0_SYS") (pintype "passive"))
    (pad "2" smd roundrect (at 0.484 0) (size 0.59 0.64) (layers "B.Cu" "B.Paste" "B.Mask") (roundrect_rratio 0.25)
      (net 9 "GND") (pintype "passive"))
  )
	(footprint "data-center-rdimm-ddr4-tester-footprints:C_0201" (layer "B.Cu")
    (at 187.1 97.425 180)
    (descr "Capacitor SMD 0201")
    (tags "capacitor SMD 0201")
    (property "Author" "Antmicro")
    (property "Dielectric" "")
    (property "License" "Apache-2.0")
    (property "MPN" "CC0201KRX6S5BB104")
    (property "Manufacturer" "Yaego")
    (property "Sheetfile" "fpga-power.kicad_sch")
    (property "Sheetname" "FPGA power")
    (property "Val" "100n")
    (property "Voltage" "")
    (property "ki_description" " ")
    (attr smd)
    (fp_text reference "C86" (at -1.12 -1.135) (layer "B.SilkS")
        (effects (font (size 0.7 0.7) (thickness 0.15)) (justify left bottom mirror))
    )
    (fp_text value "C_100n_0201" (at 0 -1.4) (layer "B.Fab") hide
        (effects (font (size 0.7 0.7) (thickness 0.15)) (justify left bottom mirror))
    )
    (fp_text user "License: Apache-2.0" (at -0.72 -4.4) (layer "B.Fab") hide
        (effects (font (size 0.7 0.7) (thickness 0.15)) (justify left bottom mirror))
    )
    (fp_text user "Author: Antmicro" (at -0.72 -5.4) (layer "B.Fab") hide
        (effects (font (size 0.7 0.7) (thickness 0.15)) (justify left bottom mirror))
    )
    (fp_text user "${REFERENCE}" (at -0.72 -3.4) (layer "B.Fab") hide
        (effects (font (size 0.7 0.7) (thickness 0.15)) (justify left bottom mirror))
    )
    (fp_rect (start -0.72 0.38) (end 0.72 -0.38)
      (stroke (width 0.05) (type solid)) (fill none) (layer "B.CrtYd"))
    (fp_rect (start 0.3 -0.15) (end -0.301 0.149)
      (stroke (width 0.15) (type solid)) (fill none) (layer "B.Fab"))
    (pad "" smd roundrect (at -0.349 0.002 180) (size 0.318 0.36) (layers "B.Paste") (roundrect_rratio 0.25))
    (pad "" smd roundrect (at 0.341 0.002 180) (size 0.318 0.36) (layers "B.Paste") (roundrect_rratio 0.25))
    (pad "1" smd roundrect (at -0.321 0.002 180) (size 0.46 0.4) (layers "B.Cu" "B.Mask") (roundrect_rratio 0.25)
      (net 143 "3V3_SYS") (pintype "passive"))
    (pad "2" smd roundrect (at 0.32 0.002 180) (size 0.46 0.4) (layers "B.Cu" "B.Mask") (roundrect_rratio 0.25)
      (net 9 "GND") (pintype "passive"))
  )
	(footprint "data-center-rdimm-ddr4-tester-footprints:C_0201" (layer "B.Cu")
    (at 178.65 78.55)
    (descr "Capacitor SMD 0201")
    (tags "capacitor SMD 0201")
    (property "Author" "Antmicro")
    (property "Dielectric" "")
    (property "License" "Apache-2.0")
    (property "MPN" "CC0201KRX6S5BB104")
    (property "Manufacturer" "Yaego")
    (property "Sheetfile" "fpga-power.kicad_sch")
    (property "Sheetname" "FPGA power")
    (property "Val" "100n")
    (property "Voltage" "")
    (property "ki_description" " ")
    (attr smd)
    (fp_text reference "C297" (at -0.54 0.37 180) (layer "B.SilkS")
        (effects (font (size 0.7 0.7) (thickness 0.15)) (justify left bottom mirror))
    )
    (fp_text value "C_100n_0201" (at 0 -1.4 180) (layer "B.Fab") hide
        (effects (font (size 0.7 0.7) (thickness 0.15)) (justify left bottom mirror))
    )
    (fp_text user "Author: Antmicro" (at -0.72 -5.4 180) (layer "B.Fab") hide
        (effects (font (size 0.7 0.7) (thickness 0.15)) (justify left bottom mirror))
    )
    (fp_text user "License: Apache-2.0" (at -0.72 -4.4 180) (layer "B.Fab") hide
        (effects (font (size 0.7 0.7) (thickness 0.15)) (justify left bottom mirror))
    )
    (fp_text user "${REFERENCE}" (at -0.72 -3.4 180) (layer "B.Fab") hide
        (effects (font (size 0.7 0.7) (thickness 0.15)) (justify left bottom mirror))
    )
    (fp_rect (start -0.72 0.38) (end 0.72 -0.38)
      (stroke (width 0.05) (type solid)) (fill none) (layer "B.CrtYd"))
    (fp_rect (start 0.3 -0.15) (end -0.301 0.149)
      (stroke (width 0.15) (type solid)) (fill none) (layer "B.Fab"))
    (pad "" smd roundrect (at -0.349 0.002) (size 0.318 0.36) (layers "B.Paste") (roundrect_rratio 0.25))
    (pad "" smd roundrect (at 0.341 0.002) (size 0.318 0.36) (layers "B.Paste") (roundrect_rratio 0.25))
    (pad "1" smd roundrect (at -0.321 0.002) (size 0.46 0.4) (layers "B.Cu" "B.Mask") (roundrect_rratio 0.25)
      (net 77 "VDDQ") (pintype "passive"))
    (pad "2" smd roundrect (at 0.32 0.002) (size 0.46 0.4) (layers "B.Cu" "B.Mask") (roundrect_rratio 0.25)
      (net 9 "GND") (pintype "passive"))
  )
	(footprint "data-center-rdimm-ddr4-tester-footprints:C_0402_1005Metric" (layer "B.Cu")
    (at 192.2 101.7)
    (descr "Capacitor SMD 0402")
    (tags "capacitor SMD 0402")
    (property "Author" "Antmicro")
    (property "Dielectric" "")
    (property "License" "Apache-2.0")
    (property "MPN" "GRM155R61A475MEAAD")
    (property "Manufacturer" "Murata")
    (property "Sheetfile" "fpga-power.kicad_sch")
    (property "Sheetname" "FPGA power")
    (property "Val" "4u7")
    (property "Voltage" "")
    (property "ki_description" " ")
    (attr smd)
    (fp_text reference "C245" (at 1.08 1.3 180) (layer "B.SilkS")
        (effects (font (size 0.7 0.7) (thickness 0.15)) (justify left bottom mirror))
    )
    (fp_text value "C_4u7_0402" (at 0 -1.4 180) (layer "B.Fab") hide
        (effects (font (size 0.7 0.7) (thickness 0.15)) (justify left bottom mirror))
    )
    (fp_text user "License: Apache-2.0" (at -0.932 -5.17 180) (layer "B.Fab") hide
        (effects (font (size 0.7 0.7) (thickness 0.15)) (justify left bottom mirror))
    )
    (fp_text user "Author: Antmicro" (at -0.932 -4.17 180) (layer "B.Fab") hide
        (effects (font (size 0.7 0.7) (thickness 0.15)) (justify left bottom mirror))
    )
    (fp_text user "${REFERENCE}" (at -0.932 -3.168 180) (layer "B.Fab") hide
        (effects (font (size 0.7 0.7) (thickness 0.15)) (justify left bottom mirror))
    )
    (fp_rect (start -0.94 0.47) (end 0.94 -0.47)
      (stroke (width 0.05) (type solid)) (fill none) (layer "B.CrtYd"))
    (fp_rect (start -0.499 0.249) (end 0.499 -0.249)
      (stroke (width 0.15) (type solid)) (fill none) (layer "B.Fab"))
    (pad "1" smd roundrect (at -0.484 0) (size 0.59 0.64) (layers "B.Cu" "B.Paste" "B.Mask") (roundrect_rratio 0.25)
      (net 147 "1V0_SYS") (pintype "passive"))
    (pad "2" smd roundrect (at 0.484 0) (size 0.59 0.64) (layers "B.Cu" "B.Paste" "B.Mask") (roundrect_rratio 0.25)
      (net 9 "GND") (pintype "passive"))
  )
	(footprint "data-center-rdimm-ddr4-tester-footprints:C_0201" (layer "B.Cu")
    (at 180.25 89.925 -90)
    (descr "Capacitor SMD 0201")
    (tags "capacitor SMD 0201")
    (property "Author" "Antmicro")
    (property "Dielectric" "")
    (property "License" "Apache-2.0")
    (property "MPN" "CC0201KRX6S5BB104")
    (property "Manufacturer" "Yaego")
    (property "Sheetfile" "fpga-power.kicad_sch")
    (property "Sheetname" "FPGA power")
    (property "Val" "100n")
    (property "Voltage" "")
    (property "ki_description" " ")
    (attr smd)
    (fp_text reference "C79" (at -0.945 0.51 90) (layer "B.SilkS")
        (effects (font (size 0.7 0.7) (thickness 0.15)) (justify left bottom mirror))
    )
    (fp_text value "C_100n_0201" (at 0 -1.4 90) (layer "B.Fab") hide
        (effects (font (size 0.7 0.7) (thickness 0.15)) (justify left bottom mirror))
    )
    (fp_text user "Author: Antmicro" (at -0.72 -5.4 90) (layer "B.Fab") hide
        (effects (font (size 0.7 0.7) (thickness 0.15)) (justify left bottom mirror))
    )
    (fp_text user "License: Apache-2.0" (at -0.72 -4.4 90) (layer "B.Fab") hide
        (effects (font (size 0.7 0.7) (thickness 0.15)) (justify left bottom mirror))
    )
    (fp_text user "${REFERENCE}" (at -0.72 -3.4 90) (layer "B.Fab") hide
        (effects (font (size 0.7 0.7) (thickness 0.15)) (justify left bottom mirror))
    )
    (fp_rect (start -0.72 0.38) (end 0.72 -0.38)
      (stroke (width 0.05) (type solid)) (fill none) (layer "B.CrtYd"))
    (fp_rect (start 0.3 -0.15) (end -0.301 0.149)
      (stroke (width 0.15) (type solid)) (fill none) (layer "B.Fab"))
    (pad "" smd roundrect (at -0.349 0.002 270) (size 0.318 0.36) (layers "B.Paste") (roundrect_rratio 0.25))
    (pad "" smd roundrect (at 0.341 0.002 270) (size 0.318 0.36) (layers "B.Paste") (roundrect_rratio 0.25))
    (pad "1" smd roundrect (at -0.321 0.002 270) (size 0.46 0.4) (layers "B.Cu" "B.Mask") (roundrect_rratio 0.25)
      (net 77 "VDDQ") (pintype "passive"))
    (pad "2" smd roundrect (at 0.32 0.002 270) (size 0.46 0.4) (layers "B.Cu" "B.Mask") (roundrect_rratio 0.25)
      (net 9 "GND") (pintype "passive"))
  )
)
